(kicad_pcb
	(version 20260206)
	(generator "pcbnew")
	(generator_version "10.0")
	(general
		(thickness 1.6)
		(legacy_teardrops no)
	)
	(paper "A4")
	(title_block
		(title "12092022_DA0F0TMDCD0_F0T_Management_Board_D_brd_V3_OCP.brd")
		(comment 1 "Grand Teton / footprint 124 of 1440 (U5), pads 222-332 of 624")
	)
	(layers
		(0 "F.Cu" signal "TOP")
		(4 "In1.Cu" signal "GND")
		(6 "In2.Cu" signal "IN1")
		(8 "In3.Cu" signal "GND1")
		(10 "In4.Cu" signal "IN2")
		(12 "In5.Cu" signal "VCC")
		(14 "In6.Cu" signal "VCC1")
		(16 "In7.Cu" signal "IN3")
		(18 "In8.Cu" signal "GND2")
		(20 "In9.Cu" signal "IN4")
		(22 "In10.Cu" signal "GND3")
		(2 "B.Cu" signal "BOTTOM")
		(9 "F.Adhes" user "F.Adhesive")
		(11 "B.Adhes" user "B.Adhesive")
		(13 "F.Paste" user "Package Geometry/Pastemask Top")
		(15 "B.Paste" user "Package Geometry/Pastemask Bottom")
		(5 "F.SilkS" user "Ref Des/Silkscreen Top")
		(7 "B.SilkS" user "Ref Des/Silkscreen Bottom")
		(1 "F.Mask" user "Board Geometry/Soldermask Top")
		(3 "B.Mask" user "Board Geometry/Soldermask Bottom")
		(17 "Dwgs.User" user "User.Drawings")
		(19 "Cmts.User" user "User.Comments")
		(21 "Eco1.User" user "User.Eco1")
		(23 "Eco2.User" user "User.Eco2")
		(25 "Edge.Cuts" user "Board Geometry/Outline")
		(27 "Margin" user)
		(31 "F.CrtYd" user "Package Geometry/Place Bound Top")
		(29 "B.CrtYd" user "Package Geometry/Place Bound Bottom")
		(35 "F.Fab" user "Ref Des/Assembly Top")
		(33 "B.Fab" user "Ref Des/Assembly Bottom")
	)
	(footprint ""
		(layer "F.Cu")
		(at 54.894988 -49.37125 180)
		(property "Reference" "U5"
			(at -11.094212 -12.07262 0)
			(unlocked yes)
			(layer "F.SilkS")
			(effects
				(font
					(size 0.7874 0.5842)
					(thickness 0.1524)
				)
				(justify left)
			)
		)
		(property "Value" ""
			(at 0 0 180)
			(layer "F.Fab")
			(effects
				(font
					(size 1.27 1.27)
				)
			)
		)
		(duplicate_pad_numbers_are_jumpers no)
		(pad "C14" smd circle
			(at 0.40005 -8.400034 180)
			(size 0.4064 0.4064)
			(layers "F.Cu" "F.Mask" "F.Paste")
			(net "V_VGAVS_R")
		)
		(pad "C15" smd circle
			(at 1.199896 -8.400034 180)
			(size 0.4064 0.4064)
			(layers "F.Cu" "F.Mask" "F.Paste")
			(net "FM_DBP_CPU_PREQ_GF_N")
		)
		(pad "C16" smd circle
			(at 1.999996 -8.400034 180)
			(size 0.4064 0.4064)
			(layers "F.Cu" "F.Mask" "F.Paste")
			(net "JTAG_1_BMC_TDO")
		)
		(pad "C17" smd circle
			(at 2.800096 -8.400034 180)
			(size 0.4064 0.4064)
			(layers "F.Cu" "F.Mask" "F.Paste")
			(net "SMB_BMC_MM16_R_SCL")
		)
		(pad "C18" smd circle
			(at 3.599942 -8.400034 180)
			(size 0.4064 0.4064)
			(layers "F.Cu" "F.Mask" "F.Paste")
			(net "SGPIO_BMC_M1_DO")
		)
		(pad "C19" smd circle
			(at 4.400042 -8.400034 180)
			(size 0.4064 0.4064)
			(layers "F.Cu" "F.Mask" "F.Paste")
			(net "SMB_BMC_MM3_R_SCL")
		)
		(pad "C20" smd circle
			(at 5.199888 -8.400034 180)
			(size 0.4064 0.4064)
			(layers "F.Cu" "F.Mask" "F.Paste")
			(net "SMB_BMC_MM4_R_SCL")
		)
		(pad "C21" smd circle
			(at 5.999988 -8.400034 180)
			(size 0.4064 0.4064)
			(layers "F.Cu" "F.Mask" "F.Paste")
			(net "BMC_EMMC_DT4")
		)
		(pad "C22" smd circle
			(at 6.800088 -8.400034 180)
			(size 0.4064 0.4064)
			(layers "F.Cu" "F.Mask" "F.Paste")
			(net "BMC_EMMC_DT2")
		)
		(pad "C23" smd circle
			(at 7.599934 -8.400034 180)
			(size 0.4064 0.4064)
			(layers "F.Cu" "F.Mask" "F.Paste")
			(net "BMC_EMMC_DT1")
		)
		(pad "C24" smd circle
			(at 8.400034 -8.400034 180)
			(size 0.4064 0.4064)
			(layers "F.Cu" "F.Mask" "F.Paste")
			(net "RMII_RXD0")
		)
		(pad "C25" smd circle
			(at 9.19988 -8.400034 180)
			(size 0.4064 0.4064)
			(layers "F.Cu" "F.Mask" "F.Paste")
			(net "RMII_OCP_RCLKI_R_ISO")
		)
		(pad "C26" smd circle
			(at 9.99998 -8.400034 180)
			(size 0.4064 0.4064)
			(layers "F.Cu" "F.Mask" "F.Paste")
			(net "FM_PLT_BMC_THERMTRIP_N_R")
		)
		(pad "D1" smd circle
			(at -9.99998 -7.599934 180)
			(size 0.4064 0.4064)
			(layers "F.Cu" "F.Mask" "F.Paste")
			(net "Net_50")
		)
		(pad "D2" smd circle
			(at -9.19988 -7.599934 180)
			(size 0.4064 0.4064)
			(layers "F.Cu" "F.Mask" "F.Paste")
			(net "Net_52")
		)
		(pad "D3" smd circle
			(at -8.400034 -7.599934 180)
			(size 0.4064 0.4064)
			(layers "F.Cu" "F.Mask" "F.Paste")
			(net "FM_BOARD_BMC_REV_ID0")
		)
		(pad "D4" smd circle
			(at -7.599934 -7.599934 180)
			(size 0.4064 0.4064)
			(layers "F.Cu" "F.Mask" "F.Paste")
			(net "Net_164")
		)
		(pad "D5" smd circle
			(at -6.800088 -7.599934 180)
			(size 0.4064 0.4064)
			(layers "F.Cu" "F.Mask" "F.Paste")
			(net "Net_43")
		)
		(pad "D6" smd circle
			(at -5.999988 -7.599934 180)
			(size 0.4064 0.4064)
			(layers "F.Cu" "F.Mask" "F.Paste")
			(net "Net_44")
		)
		(pad "D7" smd circle
			(at -5.199888 -7.599934 180)
			(size 0.4064 0.4064)
			(layers "F.Cu" "F.Mask" "F.Paste")
			(net "FM_BMC_SSPRST_N")
		)
		(pad "D8" smd circle
			(at -4.400042 -7.599934 180)
			(size 0.4064 0.4064)
			(layers "F.Cu" "F.Mask" "F.Paste")
			(net "UART_BMC_5_RXD")
		)
		(pad "D9" smd circle
			(at -3.599942 -7.599934 180)
			(size 0.4064 0.4064)
			(layers "F.Cu" "F.Mask" "F.Paste")
			(net "JTAG_SCM_TDI")
		)
		(pad "D10" smd circle
			(at -2.800096 -7.599934 180)
			(size 0.4064 0.4064)
			(layers "F.Cu" "F.Mask" "F.Paste")
			(net "BMC_CLK_25M")
		)
		(pad "D11" smd circle
			(at -1.999996 -7.599934 180)
			(size 0.4064 0.4064)
			(layers "F.Cu" "F.Mask" "F.Paste")
			(net "SMB_BMC_MM7_R_SCL")
		)
		(pad "D12" smd circle
			(at -1.199896 -7.599934 180)
			(size 0.4064 0.4064)
			(layers "F.Cu" "F.Mask" "F.Paste")
			(net "SMB_BMC_MM6_R_SCL")
		)
		(pad "D13" smd circle
			(at -0.40005 -7.599934 180)
			(size 0.4064 0.4064)
			(layers "F.Cu" "F.Mask" "F.Paste")
			(net "UART_BMC_1_RXD")
		)
		(pad "D14" smd circle
			(at 0.40005 -7.599934 180)
			(size 0.4064 0.4064)
			(layers "F.Cu" "F.Mask" "F.Paste")
			(net "H_CPU0_PROCHOT_LVC1_N")
		)
		(pad "D15" smd circle
			(at 1.199896 -7.599934 180)
			(size 0.4064 0.4064)
			(layers "F.Cu" "F.Mask" "F.Paste")
			(net "SMB_BMC_MM9_R_SCL")
		)
		(pad "D16" smd circle
			(at 1.999996 -7.599934 180)
			(size 0.4064 0.4064)
			(layers "F.Cu" "F.Mask" "F.Paste")
			(net "JTAG_1_BMC_TMS_R")
		)
		(pad "D17" smd circle
			(at 2.800096 -7.599934 180)
			(size 0.4064 0.4064)
			(layers "F.Cu" "F.Mask" "F.Paste")
			(net "JTAG_1_BMC_TRST_R")
		)
		(pad "D18" smd circle
			(at 3.599942 -7.599934 180)
			(size 0.4064 0.4064)
			(layers "F.Cu" "F.Mask" "F.Paste")
			(net "SMB_BMC_MM15_R_SCL")
		)
		(pad "D19" smd circle
			(at 4.400042 -7.599934 180)
			(size 0.4064 0.4064)
			(layers "F.Cu" "F.Mask" "F.Paste")
			(net "SMB_BMC_MM4_R_SDA")
		)
		(pad "D20" smd circle
			(at 5.199888 -7.599934 180)
			(size 0.4064 0.4064)
			(layers "F.Cu" "F.Mask" "F.Paste")
			(net "SMB_BMC_MM2_R_SDA")
		)
		(pad "D21" smd circle
			(at 5.999988 -7.599934 180)
			(size 0.4064 0.4064)
			(layers "F.Cu" "F.Mask" "F.Paste")
			(net "SMB_BMC_ALERT15_N")
		)
		(pad "D22" smd circle
			(at 6.800088 -7.599934 180)
			(size 0.4064 0.4064)
			(layers "F.Cu" "F.Mask" "F.Paste")
			(net "BMC_EMMC_CLK")
		)
		(pad "D23" smd circle
			(at 7.599934 -7.599934 180)
			(size 0.4064 0.4064)
			(layers "F.Cu" "F.Mask" "F.Paste")
			(net "BMC_EMMC_DT0")
		)
		(pad "D24" smd circle
			(at 8.400034 -7.599934 180)
			(size 0.4064 0.4064)
			(layers "F.Cu" "F.Mask" "F.Paste")
			(net "FM_BIOS_DEBUG_EN_R_N")
		)
		(pad "D25" smd circle
			(at 9.19988 -7.599934 180)
			(size 0.4064 0.4064)
			(layers "F.Cu" "F.Mask" "F.Paste")
			(net "GND")
		)
		(pad "D26" smd circle
			(at 9.99998 -7.599934 180)
			(size 0.4064 0.4064)
			(layers "F.Cu" "F.Mask" "F.Paste")
			(net "PD_BIOS_MUX_EN_R_N")
		)
		(pad "E1" smd circle
			(at -9.99998 -6.800088 180)
			(size 0.4064 0.4064)
			(layers "F.Cu" "F.Mask" "F.Paste")
			(net "Net_165")
		)
		(pad "E2" smd circle
			(at -9.19988 -6.800088 180)
			(size 0.4064 0.4064)
			(layers "F.Cu" "F.Mask" "F.Paste")
			(net "Net_48")
		)
		(pad "E3" smd circle
			(at -8.400034 -6.800088 180)
			(size 0.4064 0.4064)
			(layers "F.Cu" "F.Mask" "F.Paste")
			(net "Net_51")
		)
		(pad "E4" smd circle
			(at -7.599934 -6.800088 180)
			(size 0.4064 0.4064)
			(layers "F.Cu" "F.Mask" "F.Paste")
			(net "FM_BOARD_BMC_REV_ID1")
		)
		(pad "E5" smd circle
			(at -6.800088 -6.800088 180)
			(size 0.4064 0.4064)
			(layers "F.Cu" "F.Mask" "F.Paste")
			(net "Net_53")
		)
		(pad "E6" smd circle
			(at -5.999988 -6.800088 180)
			(size 0.4064 0.4064)
			(layers "F.Cu" "F.Mask" "F.Paste")
			(net "Net_166")
		)
		(pad "E7" smd circle
			(at -5.199888 -6.800088 180)
			(size 0.4064 0.4064)
			(layers "F.Cu" "F.Mask" "F.Paste")
			(net "P1V0_STBY_PLAVDD")
		)
		(pad "E8" smd circle
			(at -4.400042 -6.800088 180)
			(size 0.4064 0.4064)
			(layers "F.Cu" "F.Mask" "F.Paste")
			(net "GND")
		)
		(pad "E9" smd circle
			(at -3.599942 -6.800088 180)
			(size 0.4064 0.4064)
			(layers "F.Cu" "F.Mask" "F.Paste")
			(net "P1V0_STBY_PLAVDD")
		)
		(pad "E10" smd circle
			(at -2.800096 -6.800088 180)
			(size 0.4064 0.4064)
			(layers "F.Cu" "F.Mask" "F.Paste")
			(net "RST_BMC_SRST_N")
		)
		(pad "E11" smd circle
			(at -1.999996 -6.800088 180)
			(size 0.4064 0.4064)
			(layers "F.Cu" "F.Mask" "F.Paste")
			(net "SMB_BMC_MM7_R_SDA")
		)
		(pad "E12" smd circle
			(at -1.199896 -6.800088 180)
			(size 0.4064 0.4064)
			(layers "F.Cu" "F.Mask" "F.Paste")
			(net "SMB_BMC_MM8_R_SDA")
		)
		(pad "E13" smd circle
			(at -0.40005 -6.800088 180)
			(size 0.4064 0.4064)
			(layers "F.Cu" "F.Mask" "F.Paste")
			(net "SMB_BMC_MM6_R_SDA")
		)
		(pad "E14" smd circle
			(at 0.40005 -6.800088 180)
			(size 0.4064 0.4064)
			(layers "F.Cu" "F.Mask" "F.Paste")
			(net "FM_PECI_SEL_R_N")
		)
		(pad "E15" smd circle
			(at 1.199896 -6.800088 180)
			(size 0.4064 0.4064)
			(layers "F.Cu" "F.Mask" "F.Paste")
			(net "SMB_BMC_MM10_R_SCL")
		)
		(pad "E16" smd circle
			(at 1.999996 -6.800088 180)
			(size 0.4064 0.4064)
			(layers "F.Cu" "F.Mask" "F.Paste")
			(net "FLASH_WP_STATUS_R1")
		)
		(pad "E17" smd circle
			(at 2.800096 -6.800088 180)
			(size 0.4064 0.4064)
			(layers "F.Cu" "F.Mask" "F.Paste")
			(net "JTAG_1_BMC_TCK_R")
		)
		(pad "E18" smd circle
			(at 3.599942 -6.800088 180)
			(size 0.4064 0.4064)
			(layers "F.Cu" "F.Mask" "F.Paste")
			(net "SMB_BMC_MM16_R_SDA")
		)
		(pad "E19" smd circle
			(at 4.400042 -6.800088 180)
			(size 0.4064 0.4064)
			(layers "F.Cu" "F.Mask" "F.Paste")
			(net "SMB_BMC_MM2_R_SCL")
		)
		(pad "E20" smd circle
			(at 5.199888 -6.800088 180)
			(size 0.4064 0.4064)
			(layers "F.Cu" "F.Mask" "F.Paste")
			(net "BMC_EMMC_DT7")
		)
		(pad "E21" smd circle
			(at 5.999988 -6.800088 180)
			(size 0.4064 0.4064)
			(layers "F.Cu" "F.Mask" "F.Paste")
			(net "UART_6_BMC_R_TXD")
		)
		(pad "E22" smd circle
			(at 6.800088 -6.800088 180)
			(size 0.4064 0.4064)
			(layers "F.Cu" "F.Mask" "F.Paste")
			(net "BMC_EMMC_CMD")
		)
		(pad "E23" smd circle
			(at 7.599934 -6.800088 180)
			(size 0.4064 0.4064)
			(layers "F.Cu" "F.Mask" "F.Paste")
			(net "RMII_TXEN_R")
		)
		(pad "E24" smd circle
			(at 8.400034 -6.800088 180)
			(size 0.4064 0.4064)
			(layers "F.Cu" "F.Mask" "F.Paste")
			(net "RMII_TXD0_R")
		)
		(pad "E25" smd circle
			(at 9.19988 -6.800088 180)
			(size 0.4064 0.4064)
			(layers "F.Cu" "F.Mask" "F.Paste")
			(net "RMII_TXD1_R")
		)
		(pad "E26" smd circle
			(at 9.99998 -6.800088 180)
			(size 0.4064 0.4064)
			(layers "F.Cu" "F.Mask" "F.Paste")
			(net "FM_BMC_CRASHLOG_TRIG_R1_N")
		)
		(pad "F1" smd circle
			(at -9.99998 -5.999988 180)
			(size 0.4064 0.4064)
			(layers "F.Cu" "F.Mask" "F.Paste")
			(net "M_BMC_DDR4_MA<2>")
		)
		(pad "F2" smd circle
			(at -9.19988 -5.999988 180)
			(size 0.4064 0.4064)
			(layers "F.Cu" "F.Mask" "F.Paste")
			(net "M_BMC_DDR4_MA<10>")
		)
		(pad "F3" smd circle
			(at -8.400034 -5.999988 180)
			(size 0.4064 0.4064)
			(layers "F.Cu" "F.Mask" "F.Paste")
			(net "M_BMC_DDR4_MA<0>")
		)
		(pad "F4" smd circle
			(at -7.599934 -5.999988 180)
			(size 0.4064 0.4064)
			(layers "F.Cu" "F.Mask" "F.Paste")
			(net "Net_49")
		)
		(pad "F5" smd circle
			(at -6.800088 -5.999988 180)
			(size 0.4064 0.4064)
			(layers "F.Cu" "F.Mask" "F.Paste")
			(net "FM_BOARD_BMC_REV_ID2")
		)
		(pad "F6" smd circle
			(at -5.999988 -5.999988 180)
			(size 0.4064 0.4064)
			(layers "F.Cu" "F.Mask" "F.Paste")
			(net "GND")
		)
		(pad "F7" smd circle
			(at -5.199888 -5.999988 180)
			(size 0.4064 0.4064)
			(layers "F.Cu" "F.Mask" "F.Paste")
			(net "P1V0_STBY_PLAVDD")
		)
		(pad "F8" smd circle
			(at -4.400042 -5.999988 180)
			(size 0.4064 0.4064)
			(layers "F.Cu" "F.Mask" "F.Paste")
			(net "GND")
		)
		(pad "F9" smd circle
			(at -3.599942 -5.999988 180)
			(size 0.4064 0.4064)
			(layers "F.Cu" "F.Mask" "F.Paste")
			(net "P1V0_STBY_PLAVDD")
		)
		(pad "F10" smd circle
			(at -2.800096 -5.999988 180)
			(size 0.4064 0.4064)
			(layers "F.Cu" "F.Mask" "F.Paste")
			(net "GND")
		)
		(pad "F11" smd circle
			(at -1.999996 -5.999988 180)
			(size 0.4064 0.4064)
			(layers "F.Cu" "F.Mask" "F.Paste")
			(net "JTAG_SCM_NTRST")
		)
		(pad "F12" smd circle
			(at -1.199896 -5.999988 180)
			(size 0.4064 0.4064)
			(layers "F.Cu" "F.Mask" "F.Paste")
			(net "GND")
		)
		(pad "F13" smd circle
			(at -0.40005 -5.999988 180)
			(size 0.4064 0.4064)
			(layers "F.Cu" "F.Mask" "F.Paste")
			(net "SMB_BMC_MM8_R_SCL")
		)
		(pad "F14" smd circle
			(at 0.40005 -5.999988 180)
			(size 0.4064 0.4064)
			(layers "F.Cu" "F.Mask" "F.Paste")
			(net "GND")
		)
		(pad "F15" smd circle
			(at 1.199896 -5.999988 180)
			(size 0.4064 0.4064)
			(layers "F.Cu" "F.Mask" "F.Paste")
			(net "FM_JTAG_TCK_MUX_BMC_SEL_R1")
		)
		(pad "F16" smd circle
			(at 1.999996 -5.999988 180)
			(size 0.4064 0.4064)
			(layers "F.Cu" "F.Mask" "F.Paste")
			(net "GND")
		)
		(pad "F17" smd circle
			(at 2.800096 -5.999988 180)
			(size 0.4064 0.4064)
			(layers "F.Cu" "F.Mask" "F.Paste")
			(net "GND")
		)
		(pad "F18" smd circle
			(at 3.599942 -5.999988 180)
			(size 0.4064 0.4064)
			(layers "F.Cu" "F.Mask" "F.Paste")
			(net "GND")
		)
		(pad "F19" smd circle
			(at 4.400042 -5.999988 180)
			(size 0.4064 0.4064)
			(layers "F.Cu" "F.Mask" "F.Paste")
			(net "P3V3_P1V8_I2C_I3C")
		)
		(pad "F20" smd circle
			(at 5.199888 -5.999988 180)
			(size 0.4064 0.4064)
			(layers "F.Cu" "F.Mask" "F.Paste")
			(net "P3V3_P1V8_I2C_I3C")
		)
		(pad "F21" smd circle
			(at 5.999988 -5.999988 180)
			(size 0.4064 0.4064)
			(layers "F.Cu" "F.Mask" "F.Paste")
			(net "GND")
		)
		(pad "F22" smd circle
			(at 6.800088 -5.999988 180)
			(size 0.4064 0.4064)
			(layers "F.Cu" "F.Mask" "F.Paste")
			(net "H_CPU_CATERR_LVC2_R2_N")
		)
		(pad "F23" smd circle
			(at 7.599934 -5.999988 180)
			(size 0.4064 0.4064)
			(layers "F.Cu" "F.Mask" "F.Paste")
			(net "GPU_FPGA_RST_N")
		)
		(pad "F24" smd circle
			(at 8.400034 -5.999988 180)
			(size 0.4064 0.4064)
			(layers "F.Cu" "F.Mask" "F.Paste")
			(net "IRQ_SML0_ALERT_R_N")
		)
		(pad "F25" smd circle
			(at 9.19988 -5.999988 180)
			(size 0.4064 0.4064)
			(layers "F.Cu" "F.Mask" "F.Paste")
			(net "FM_BIC_DEBUG_SW_N_R")
		)
		(pad "F26" smd circle
			(at 9.99998 -5.999988 180)
			(size 0.4064 0.4064)
			(layers "F.Cu" "F.Mask" "F.Paste")
			(net "CLK_BUF1_GPU_FPGA_OE_R_N")
		)
		(pad "G1" smd circle
			(at -9.99998 -5.199888 180)
			(size 0.4064 0.4064)
			(layers "F.Cu" "F.Mask" "F.Paste")
			(net "M_BMC_DDR4_MA<11>")
		)
		(pad "G2" smd circle
			(at -9.19988 -5.199888 180)
			(size 0.4064 0.4064)
			(layers "F.Cu" "F.Mask" "F.Paste")
			(net "GND")
		)
		(pad "G3" smd circle
			(at -8.400034 -5.199888 180)
			(size 0.4064 0.4064)
			(layers "F.Cu" "F.Mask" "F.Paste")
			(net "M_BMC_DDR4_MBG0")
		)
		(pad "G4" smd circle
			(at -7.599934 -5.199888 180)
			(size 0.4064 0.4064)
			(layers "F.Cu" "F.Mask" "F.Paste")
			(net "M_BMC_DDR4_MBA0")
		)
		(pad "G5" smd circle
			(at -6.800088 -5.199888 180)
			(size 0.4064 0.4064)
			(layers "F.Cu" "F.Mask" "F.Paste")
			(net "M_BMC_DDR4_MWE_N")
		)
		(pad "G6" smd circle
			(at -5.999988 -5.199888 180)
			(size 0.4064 0.4064)
			(layers "F.Cu" "F.Mask" "F.Paste")
			(net "P1V2_AUX")
		)
		(pad "G21" smd circle
			(at 5.999988 -5.199888 180)
			(size 0.4064 0.4064)
			(layers "F.Cu" "F.Mask" "F.Paste")
			(net "P3V3_P1V8_SD1VDD")
		)
		(pad "G22" smd circle
			(at 6.800088 -5.199888 180)
			(size 0.4064 0.4064)
			(layers "F.Cu" "F.Mask" "F.Paste")
			(net "RST_ROT_CPU_R1_N")
		)
		(pad "G23" smd circle
			(at 7.599934 -5.199888 180)
			(size 0.4064 0.4064)
			(layers "F.Cu" "F.Mask" "F.Paste")
			(net "FM_JTAG_SEL")
		)
		(pad "G24" smd circle
			(at 8.400034 -5.199888 180)
			(size 0.4064 0.4064)
			(layers "F.Cu" "F.Mask" "F.Paste")
			(net "IRQ_SGPIO_BMC_N")
		)
		(pad "G25" smd circle
			(at 9.19988 -5.199888 180)
			(size 0.4064 0.4064)
			(layers "F.Cu" "F.Mask" "F.Paste")
			(net "GND")
		)
		(pad "G26" smd circle
			(at 9.99998 -5.199888 180)
			(size 0.4064 0.4064)
			(layers "F.Cu" "F.Mask" "F.Paste")
			(net "FM_ID_LED")
		)
		(pad "H1" smd circle
			(at -9.99998 -4.400042 180)
			(size 0.4064 0.4064)
			(layers "F.Cu" "F.Mask" "F.Paste")
			(net "M_BMC_DDR4_MACT_N")
		)
		(pad "H2" smd circle
			(at -9.19988 -4.400042 180)
			(size 0.4064 0.4064)
			(layers "F.Cu" "F.Mask" "F.Paste")
			(net "M_BMC_DDR4_MCS_N")
		)
		(pad "H3" smd circle
			(at -8.400034 -4.400042 180)
			(size 0.4064 0.4064)
			(layers "F.Cu" "F.Mask" "F.Paste")
			(net "M_BMC_DDR4_MA<3>")
		)
		(pad "H4" smd circle
			(at -7.599934 -4.400042 180)
			(size 0.4064 0.4064)
			(layers "F.Cu" "F.Mask" "F.Paste")
			(net "GND")
		)
		(pad "H5" smd circle
			(at -6.800088 -4.400042 180)
			(size 0.4064 0.4064)
			(layers "F.Cu" "F.Mask" "F.Paste")
			(net "M_BMC_DDR4_MBA1")
		)
		(pad "H6" smd circle
			(at -5.999988 -4.400042 180)
			(size 0.4064 0.4064)
			(layers "F.Cu" "F.Mask" "F.Paste")
			(net "P1V2_AUX")
		)
		(pad "H8" smd circle
			(at -4.400042 -4.400042 180)
			(size 0.4064 0.4064)
			(layers "F.Cu" "F.Mask" "F.Paste")
			(net "P1V8_AUX")
		)
		(pad "H9" smd circle
			(at -3.599942 -4.400042 180)
			(size 0.4064 0.4064)
			(layers "F.Cu" "F.Mask" "F.Paste")
			(net "GND")
		)
	)
)
